# BASEBOARD_FAB2 (Tioga Pass) — schematic netlist excerpt (pin names and nets, part order shuffled) for the footprints in the layout excerpt that follows; sources: Cadence DE-HDL packaged netlist, KiCad conversion of Wiwynn_Tioga_Pass_MB.brd

C8E15  CAP  0.022UF 16V 10% X7R  pkg 0402LF  page 241 : A = VR_P5V_STBY_SS ; B = AGND_P5V_STBY
T1P33  TPAD-SE-2P-GP  pkg DISCRET-GA1  page 256 : \1\ = L5_50OHM_6INCH ; GND1 = GND
CF12  SC22P50V2JN-4GP  5%  pkg SMD-BCG  page 206 : \1\ = VR_PVSA_CPU1_BIREF1 ; \2\ = ISENSE_PVSA_CPU1_IMON

(kicad_pcb
	(version 20260206)
	(generator "pcbnew")
	(generator_version "10.0")
	(general
		(thickness 1.6)
		(legacy_teardrops no)
	)
	(paper "A4")
	(title_block
		(title "Wiwynn_Tioga_Pass_MB.brd")
		(comment 1 "Tioga Pass / footprints 771-773 of 4770")
	)
	(layers
		(0 "F.Cu" signal "TOP")
		(4 "In1.Cu" signal "L2GND")
		(6 "In2.Cu" signal "L3")
		(8 "In3.Cu" signal "L4GND")
		(10 "In4.Cu" signal "L5")
		(12 "In5.Cu" signal "L6GND")
		(14 "In6.Cu" signal "L7VCC")
		(16 "In7.Cu" signal "L8VCC")
		(18 "In8.Cu" signal "L9GND")
		(20 "In9.Cu" signal "L10")
		(22 "In10.Cu" signal "L11GND")
		(24 "In11.Cu" signal "L12")
		(26 "In12.Cu" signal "L13GND")
		(2 "B.Cu" signal "BOTTOM")
		(9 "F.Adhes" user "F.Adhesive")
		(11 "B.Adhes" user "B.Adhesive")
		(13 "F.Paste" user "Package Geometry/Pastemask Top")
		(15 "B.Paste" user "Package Geometry/Pastemask Bottom")
		(5 "F.SilkS" user "Ref Des/Silkscreen Top")
		(7 "B.SilkS" user "Ref Des/Silkscreen Bottom")
		(1 "F.Mask" user "Board Geometry/Soldermask Top")
		(3 "B.Mask" user "Board Geometry/Soldermask Bottom")
		(17 "Dwgs.User" user "User.Drawings")
		(19 "Cmts.User" user "User.Comments")
		(21 "Eco1.User" user "User.Eco1")
		(23 "Eco2.User" user "User.Eco2")
		(25 "Edge.Cuts" user "Board Geometry/Outline")
		(27 "Margin" user)
		(31 "F.CrtYd" user "Package Geometry/Place Bound Top")
		(29 "B.CrtYd" user "Package Geometry/Place Bound Bottom")
		(35 "F.Fab" user "Ref Des/Assembly Top")
		(33 "B.Fab" user "Ref Des/Assembly Bottom")
	)
	(footprint ""
		(layer "F.Cu")
		(at 394.8176 -66.6242)
		(property "Reference" "C8E15"
			(at 0 0 0)
			(layer "F.SilkS")
			(hide yes)
			(effects
				(font
					(size 1.27 1.27)
				)
			)
		)
		(property "Value" ""
			(at 0 0 0)
			(layer "F.Fab")
			(effects
				(font
					(size 1.27 1.27)
				)
			)
		)
		(duplicate_pad_numbers_are_jumpers no)
		(fp_poly
			(pts
				(xy 0.3048 -0.1016) (xy 0.3048 0.9906) (xy -0.3048 0.9906) (xy -0.3048 -0.1016)
			)
			(stroke
				(width 0)
				(type default)
			)
			(fill no)
			(layer "F.CrtYd")
		)
		(fp_line
			(start -0.3048 -0.1016)
			(end -0.3048 0.9906)
			(stroke
				(width 0.1)
				(type default)
			)
			(layer "F.Fab")
		)
		(fp_line
			(start -0.3048 0.9906)
			(end 0.3048 0.9906)
			(stroke
				(width 0.1)
				(type default)
			)
			(layer "F.Fab")
		)
		(fp_line
			(start 0.3048 -0.1016)
			(end -0.3048 -0.1016)
			(stroke
				(width 0.1)
				(type default)
			)
			(layer "F.Fab")
		)
		(fp_line
			(start 0.3048 0.9906)
			(end 0.3048 -0.1016)
			(stroke
				(width 0.1)
				(type default)
			)
			(layer "F.Fab")
		)
		(pad "1" smd rect
			(at 0 0)
			(size 0.508 0.508)
			(layers "F.Cu" "F.Mask" "F.Paste")
			(net "VR_P5V_STBY_SS")
		)
		(pad "2" smd rect
			(at 0 0.889)
			(size 0.508 0.508)
			(layers "F.Cu" "F.Mask" "F.Paste")
			(net "AGND_P5V_STBY")
		)
		(zone
			(layer "F.Cu")
			(hatch none 0.5)
			(connect_pads
				(clearance 0)
			)
			(min_thickness 0.25)
			(keepout
				(tracks allowed)
				(vias not_allowed)
				(pads allowed)
				(copperpour not_allowed)
				(footprints allowed)
			)
			(placement
				(enabled no)
				(sheetname "")
			)
			(fill
				(thermal_gap 0.5)
				(thermal_bridge_width 0.5)
				(island_removal_mode 0)
			)
			(polygon
				(pts
					(xy 394.5636 -66.3702) (xy 395.0716 -66.3702) (xy 395.0716 -65.9892) (xy 394.5636 -65.9892)
				)
			)
		)
		(zone
			(layer "F.Cu")
			(hatch none 0.5)
			(connect_pads
				(clearance 0)
			)
			(min_thickness 0.25)
			(keepout
				(tracks not_allowed)
				(vias allowed)
				(pads allowed)
				(copperpour not_allowed)
				(footprints allowed)
			)
			(placement
				(enabled no)
				(sheetname "")
			)
			(fill
				(thermal_gap 0.5)
				(thermal_bridge_width 0.5)
				(island_removal_mode 0)
			)
			(polygon
				(pts
					(xy 394.5636 -65.9892) (xy 395.0716 -65.9892) (xy 395.0716 -66.3702) (xy 394.5636 -66.3702)
				)
			)
		)
	)
	(footprint ""
		(layer "F.Cu")
		(at 19.177 13.2715 -90)
		(property "Reference" "T1P33"
			(at 0 0 270)
			(layer "F.SilkS")
			(hide yes)
			(effects
				(font
					(size 1.27 1.27)
				)
			)
		)
		(property "Value" "*"
			(at 0 -3.44805 270)
			(unlocked yes)
			(layer "F.Fab")
			(hide yes)
			(effects
				(font
					(size 0.889 0.889)
					(thickness 0.1524)
				)
			)
		)
		(property "Device Type" "TPAD-SE-2P-GP_DISCRET-GA1-TPADA"
			(at 0 -4.97205 270)
			(unlocked yes)
			(layer "F.Fab")
			(hide yes)
			(effects
				(font
					(size 0.889 0.889)
					(thickness 0.1524)
				)
			)
		)
		(duplicate_pad_numbers_are_jumpers no)
		(fp_line
			(start -1.016 2.286)
			(end -1.016 -2.286)
			(stroke
				(width 0.1524)
				(type default)
			)
			(layer "F.SilkS")
		)
		(fp_line
			(start 1.016 2.286)
			(end -1.016 2.286)
			(stroke
				(width 0.1524)
				(type default)
			)
			(layer "F.SilkS")
		)
		(fp_line
			(start -1.016 -2.286)
			(end 1.016 -2.286)
			(stroke
				(width 0.1524)
				(type default)
			)
			(layer "F.SilkS")
		)
		(fp_line
			(start 1.016 -2.286)
			(end 1.016 2.286)
			(stroke
				(width 0.1524)
				(type default)
			)
			(layer "F.SilkS")
		)
		(fp_rect
			(start -1.27 2.54)
			(end 1.27 -2.54)
			(stroke
				(width 0)
				(type default)
			)
			(fill no)
			(layer "F.CrtYd")
		)
		(fp_rect
			(start -1.27 2.54)
			(end 1.27 -2.54)
			(stroke
				(width 0)
				(type default)
			)
			(fill no)
			(layer "F.Fab")
		)
		(pad "1" thru_hole circle
			(at 0 -1.27 270)
			(size 1.524 1.524)
			(drill 0.9144)
			(layers "*.Cu" "*.Mask")
			(remove_unused_layers no)
			(net "L5_50OHM_6INCH")
			(clearance -0.0508)
			(thermal_gap 0.127)
			(padstack
				(mode front_inner_back)
				(layer "Inner"
					(shape circle)
					(size 1.1684 1.1684)
					(clearance 0.127)
				)
				(layer "B.Cu"
					(shape circle)
					(size 1.524 1.524)
					(clearance -0.0508)
				)
			)
		)
		(pad "GND1" thru_hole rect
			(at 0 1.27 270)
			(size 1.524 1.524)
			(drill 0.9144)
			(layers "*.Cu" "*.Mask")
			(remove_unused_layers no)
			(net "GND")
			(clearance -0.0508)
			(thermal_gap 0.127)
			(padstack
				(mode front_inner_back)
				(layer "Inner"
					(shape circle)
					(size 1.1684 1.1684)
					(clearance 0.127)
				)
				(layer "B.Cu"
					(shape rect)
					(size 1.524 1.524)
					(clearance -0.0508)
				)
			)
		)
	)
	(footprint ""
		(layer "F.Cu")
		(at 24.518112 -98.003868 180)
		(property "Reference" "CF12"
			(at 0 0 180)
			(layer "F.SilkS")
			(hide yes)
			(effects
				(font
					(size 1.27 1.27)
				)
			)
		)
		(property "Value" "*"
			(at 1.1811 -2.8194 180)
			(unlocked yes)
			(layer "F.Fab")
			(hide yes)
			(effects
				(font
					(size 1.27 1.016)
					(thickness 0.1524)
				)
			)
		)
		(property "Device Type" "SC22P50V2JN-4GP_SMD-BCG-SC22P5A"
			(at 1.1811 -4.3434 180)
			(unlocked yes)
			(layer "F.Fab")
			(hide yes)
			(effects
				(font
					(size 1.27 1.016)
					(thickness 0.1524)
				)
			)
		)
		(duplicate_pad_numbers_are_jumpers no)
		(fp_rect
			(start -0.4318 0.9525)
			(end 0.4318 -0.9525)
			(stroke
				(width 0)
				(type default)
			)
			(fill no)
			(layer "F.CrtYd")
		)
		(fp_rect
			(start -0.4318 0.9525)
			(end 0.4318 -0.9525)
			(stroke
				(width 0)
				(type default)
			)
			(fill no)
			(layer "F.Fab")
		)
		(pad "1" smd custom
			(at 0 -0.4445 180)
			(size 0.1524 0.1524)
			(layers "F.Cu" "F.Mask" "F.Paste")
			(net "VR_PVSA_CPU1_BIREF1")
			(options
				(clearance outline)
				(anchor circle)
			)
			(primitives
				(gr_poly
					(pts
						(arc
							(start 0.3048 -0.2032)
							(mid 0.275042 -0.275042)
							(end 0.2032 -0.3048)
						)
						(arc
							(start -0.2032 -0.3048)
							(mid -0.275042 -0.275042)
							(end -0.3048 -0.2032)
						)
						(arc
							(start -0.3048 0.2032)
							(mid -0.275042 0.275042)
							(end -0.2032 0.3048)
						)
						(arc
							(start 0.2032 0.3048)
							(mid 0.275042 0.275042)
							(end 0.3048 0.2032)
						)
					)
					(width 0)
					(fill yes)
				)
			)
		)
		(pad "2" smd custom
			(at 0 0.4445 180)
			(size 0.1524 0.1524)
			(layers "F.Cu" "F.Mask" "F.Paste")
			(net "ISENSE_PVSA_CPU1_IMON")
			(options
				(clearance outline)
				(anchor circle)
			)
			(primitives
				(gr_poly
					(pts
						(arc
							(start 0.3048 -0.2032)
							(mid 0.275042 -0.275042)
							(end 0.2032 -0.3048)
						)
						(arc
							(start -0.2032 -0.3048)
							(mid -0.275042 -0.275042)
							(end -0.3048 -0.2032)
						)
						(arc
							(start -0.3048 0.2032)
							(mid -0.275042 0.275042)
							(end -0.2032 0.3048)
						)
						(arc
							(start 0.2032 0.3048)
							(mid 0.275042 0.275042)
							(end 0.3048 0.2032)
						)
					)
					(width 0)
					(fill yes)
				)
			)
		)
	)
)
